# T6G (Grand Teton) — schematic netlist excerpt (pin names and nets, part order shuffled) for the footprints in the layout excerpt that follows; sources: Cadence DE-HDL packaged netlist, KiCad conversion of 04192023_DAF0TMB3IC0_F0TG_MB_C_brd_V02_OCP.brd

R6116  Q_RES  0 5% CHIP  pkg 0402LF  page 80 : A = E1S_0_PERST1_CLKREQ_R_N ; B = E1S_0_PRSNT_N
R8086  Q_RES  0 5% CHIP  pkg 0402LF  page 98 : A = PWRGD_CHAF_CPU1 ; B = PWRGD_CHAF_CPU1_R1

(kicad_pcb
	(version 20260206)
	(generator "pcbnew")
	(generator_version "10.0")
	(general
		(thickness 1.6)
		(legacy_teardrops no)
	)
	(paper "A4")
	(title_block
		(title "04192023_DAF0TMB3IC0_F0TG_MB_C_brd_V02_OCP.brd")
		(comment 1 "Grand Teton / footprints 4645-4646 of 8354")
	)
	(layers
		(0 "F.Cu" signal "TOP")
		(4 "In1.Cu" signal "GND")
		(6 "In2.Cu" signal "IN1")
		(8 "In3.Cu" signal "GND1")
		(10 "In4.Cu" signal "IN2")
		(12 "In5.Cu" signal "GND2")
		(14 "In6.Cu" signal "IN3")
		(16 "In7.Cu" signal "GND3")
		(18 "In8.Cu" signal "VCC")
		(20 "In9.Cu" signal "VCC1")
		(22 "In10.Cu" signal "GND4")
		(24 "In11.Cu" signal "IN4")
		(26 "In12.Cu" signal "GND5")
		(28 "In13.Cu" signal "IN5")
		(30 "In14.Cu" signal "GND6")
		(32 "In15.Cu" signal "IN6")
		(34 "In16.Cu" signal "GND7")
		(2 "B.Cu" signal "BOTTOM")
		(9 "F.Adhes" user "F.Adhesive")
		(11 "B.Adhes" user "B.Adhesive")
		(13 "F.Paste" user "Package Geometry/Pastemask Top")
		(15 "B.Paste" user "Package Geometry/Pastemask Bottom")
		(5 "F.SilkS" user "Ref Des/Silkscreen Top")
		(7 "B.SilkS" user "Ref Des/Silkscreen Bottom")
		(1 "F.Mask" user "Board Geometry/Soldermask Top")
		(3 "B.Mask" user "Board Geometry/Soldermask Bottom")
		(17 "Dwgs.User" user "User.Drawings")
		(19 "Cmts.User" user "User.Comments")
		(21 "Eco1.User" user "User.Eco1")
		(23 "Eco2.User" user "User.Eco2")
		(25 "Edge.Cuts" user "Board Geometry/Outline")
		(27 "Margin" user)
		(31 "F.CrtYd" user "Package Geometry/Place Bound Top")
		(29 "B.CrtYd" user "Package Geometry/Place Bound Bottom")
		(35 "F.Fab" user "Ref Des/Assembly Top")
		(33 "B.Fab" user "Ref Des/Assembly Bottom")
	)
	(footprint ""
		(layer "F.Cu")
		(at 160.274762 -111.221774 180)
		(property "Reference" "R6116"
			(at 0 0 180)
			(layer "F.SilkS")
			(hide yes)
			(effects
				(font
					(size 1.27 1.27)
				)
			)
		)
		(property "Value" ""
			(at 0 0 180)
			(layer "F.Fab")
			(effects
				(font
					(size 1.27 1.27)
				)
			)
		)
		(duplicate_pad_numbers_are_jumpers no)
		(fp_line
			(start 0.7874 0.4064)
			(end -0.7874 0.4064)
			(stroke
				(width 0.1524)
				(type default)
			)
			(layer "F.SilkS")
		)
		(fp_line
			(start 0.7874 -0.4064)
			(end 0.7874 0.4064)
			(stroke
				(width 0.1524)
				(type default)
			)
			(layer "F.SilkS")
		)
		(fp_line
			(start -0.7874 0.4064)
			(end -0.7874 -0.4064)
			(stroke
				(width 0.1524)
				(type default)
			)
			(layer "F.SilkS")
		)
		(fp_line
			(start -0.7874 -0.4064)
			(end 0.7874 -0.4064)
			(stroke
				(width 0.1524)
				(type default)
			)
			(layer "F.SilkS")
		)
		(fp_line
			(start 0.67945 0.3048)
			(end 0.120396 0.3048)
			(stroke
				(width 0.1)
				(type default)
			)
			(layer "F.Fab")
		)
		(fp_line
			(start 0.67945 -0.3048)
			(end 0.67945 0.3048)
			(stroke
				(width 0.1)
				(type default)
			)
			(layer "F.Fab")
		)
		(fp_line
			(start 0.12065 -0.2794)
			(end 0.12065 -0.3048)
			(stroke
				(width 0.1)
				(type default)
			)
			(layer "F.Fab")
		)
		(fp_line
			(start 0.12065 -0.3048)
			(end 0.67945 -0.3048)
			(stroke
				(width 0.1)
				(type default)
			)
			(layer "F.Fab")
		)
		(fp_line
			(start 0.120396 0.3048)
			(end 0.120396 0.2794)
			(stroke
				(width 0.1)
				(type default)
			)
			(layer "F.Fab")
		)
		(fp_line
			(start 0.120396 0.2794)
			(end -0.12065 0.2794)
			(stroke
				(width 0.1)
				(type default)
			)
			(layer "F.Fab")
		)
		(fp_line
			(start -0.12065 0.3048)
			(end -0.67945 0.3048)
			(stroke
				(width 0.1)
				(type default)
			)
			(layer "F.Fab")
		)
		(fp_line
			(start -0.12065 0.2794)
			(end -0.12065 0.3048)
			(stroke
				(width 0.1)
				(type default)
			)
			(layer "F.Fab")
		)
		(fp_line
			(start -0.12065 -0.2794)
			(end 0.12065 -0.2794)
			(stroke
				(width 0.1)
				(type default)
			)
			(layer "F.Fab")
		)
		(fp_line
			(start -0.12065 -0.305054)
			(end -0.12065 -0.2794)
			(stroke
				(width 0.1)
				(type default)
			)
			(layer "F.Fab")
		)
		(fp_line
			(start -0.67945 0.3048)
			(end -0.67945 -0.305054)
			(stroke
				(width 0.1)
				(type default)
			)
			(layer "F.Fab")
		)
		(fp_line
			(start -0.67945 -0.305054)
			(end -0.12065 -0.305054)
			(stroke
				(width 0.1)
				(type default)
			)
			(layer "F.Fab")
		)
		(pad "1" smd circle
			(at -0.40005 0 180)
			(size 0 0)
			(layers "F.Cu" "F.Mask" "F.Paste")
			(net "E1S_0_PERST1_CLKREQ_R_N")
		)
		(pad "2" smd circle
			(at 0.40005 0 180)
			(size 0 0)
			(layers "F.Cu" "F.Mask" "F.Paste")
			(net "E1S_0_PRSNT_N")
		)
	)
	(footprint ""
		(layer "F.Cu")
		(at 146.939 -120.777)
		(property "Reference" "R8086"
			(at 0 0 0)
			(layer "F.SilkS")
			(hide yes)
			(effects
				(font
					(size 1.27 1.27)
				)
			)
		)
		(property "Value" ""
			(at 0 0 0)
			(layer "F.Fab")
			(effects
				(font
					(size 1.27 1.27)
				)
			)
		)
		(duplicate_pad_numbers_are_jumpers no)
		(fp_line
			(start -0.7874 -0.4064)
			(end 0.7874 -0.4064)
			(stroke
				(width 0.1524)
				(type default)
			)
			(layer "F.SilkS")
		)
		(fp_line
			(start -0.7874 0.4064)
			(end -0.7874 -0.4064)
			(stroke
				(width 0.1524)
				(type default)
			)
			(layer "F.SilkS")
		)
		(fp_line
			(start 0.7874 -0.4064)
			(end 0.7874 0.4064)
			(stroke
				(width 0.1524)
				(type default)
			)
			(layer "F.SilkS")
		)
		(fp_line
			(start 0.7874 0.4064)
			(end -0.7874 0.4064)
			(stroke
				(width 0.1524)
				(type default)
			)
			(layer "F.SilkS")
		)
		(fp_line
			(start -0.67945 -0.305054)
			(end -0.12065 -0.305054)
			(stroke
				(width 0.1)
				(type default)
			)
			(layer "F.Fab")
		)
		(fp_line
			(start -0.67945 0.3048)
			(end -0.67945 -0.305054)
			(stroke
				(width 0.1)
				(type default)
			)
			(layer "F.Fab")
		)
		(fp_line
			(start -0.12065 -0.305054)
			(end -0.12065 -0.2794)
			(stroke
				(width 0.1)
				(type default)
			)
			(layer "F.Fab")
		)
		(fp_line
			(start -0.12065 -0.2794)
			(end 0.12065 -0.2794)
			(stroke
				(width 0.1)
				(type default)
			)
			(layer "F.Fab")
		)
		(fp_line
			(start -0.12065 0.2794)
			(end -0.12065 0.3048)
			(stroke
				(width 0.1)
				(type default)
			)
			(layer "F.Fab")
		)
		(fp_line
			(start -0.12065 0.3048)
			(end -0.67945 0.3048)
			(stroke
				(width 0.1)
				(type default)
			)
			(layer "F.Fab")
		)
		(fp_line
			(start 0.120396 0.2794)
			(end -0.12065 0.2794)
			(stroke
				(width 0.1)
				(type default)
			)
			(layer "F.Fab")
		)
		(fp_line
			(start 0.120396 0.3048)
			(end 0.120396 0.2794)
			(stroke
				(width 0.1)
				(type default)
			)
			(layer "F.Fab")
		)
		(fp_line
			(start 0.12065 -0.3048)
			(end 0.67945 -0.3048)
			(stroke
				(width 0.1)
				(type default)
			)
			(layer "F.Fab")
		)
		(fp_line
			(start 0.12065 -0.2794)
			(end 0.12065 -0.3048)
			(stroke
				(width 0.1)
				(type default)
			)
			(layer "F.Fab")
		)
		(fp_line
			(start 0.67945 -0.3048)
			(end 0.67945 0.3048)
			(stroke
				(width 0.1)
				(type default)
			)
			(layer "F.Fab")
		)
		(fp_line
			(start 0.67945 0.3048)
			(end 0.120396 0.3048)
			(stroke
				(width 0.1)
				(type default)
			)
			(layer "F.Fab")
		)
		(pad "1" smd circle
			(at -0.40005 0)
			(size 0 0)
			(layers "F.Cu" "F.Mask" "F.Paste")
			(net "PWRGD_CHAF_CPU1")
		)
		(pad "2" smd circle
			(at 0.40005 0)
			(size 0 0)
			(layers "F.Cu" "F.Mask" "F.Paste")
			(net "PWRGD_CHAF_CPU1_R1")
		)
	)
)
